# SI test board — KiCad project settings (.kicad_pro: net classes, design rules, text variables)
{
  "board": {
    "design_settings": {
      "defaults": {
        "board_outline_line_width": 0.09999999999999999,
        "copper_line_width": 0.19999999999999998,
        "copper_text_italic": false,
        "copper_text_size_h": 1.5,
        "copper_text_size_v": 1.5,
        "copper_text_thickness": 0.3,
        "copper_text_upright": false,
        "courtyard_line_width": 0.049999999999999996,
        "dimension_precision": 4,
        "dimension_units": 3,
        "dimensions": {
          "arrow_length": 1270000,
          "extension_offset": 500000,
          "keep_text_aligned": true,
          "suppress_zeroes": false,
          "text_position": 0,
          "units_format": 1
        },
        "fab_line_width": 0.09999999999999999,
        "fab_text_italic": false,
        "fab_text_size_h": 1.0,
        "fab_text_size_v": 1.0,
        "fab_text_thickness": 0.15,
        "fab_text_upright": false,
        "other_line_width": 0.15,
        "other_text_italic": false,
        "other_text_size_h": 1.0,
        "other_text_size_v": 1.0,
        "other_text_thickness": 0.15,
        "other_text_upright": false,
        "pads": {
          "drill": 0.762,
          "height": 1.524,
          "width": 1.524
        },
        "silk_line_width": 0.15,
        "silk_text_italic": false,
        "silk_text_size_h": 1.0,
        "silk_text_size_v": 1.0,
        "silk_text_thickness": 0.15,
        "silk_text_upright": false,
        "zones": {
          "45_degree_only": false,
          "min_clearance": 0.508
        }
      },
      "diff_pair_dimensions": [
        {
          "gap": 0.0,
          "via_gap": 0.0,
          "width": 0.0
        }
      ],
      "drc_exclusions": [],
      "meta": {
        "version": 2
      },
      "rule_severities": {
        "annular_width": "error",
        "clearance": "error",
        "copper_edge_clearance": "error",
        "courtyards_overlap": "error",
        "diff_pair_gap_out_of_range": "error",
        "diff_pair_uncoupled_length_too_long": "error",
        "drill_out_of_range": "error",
        "duplicate_footprints": "warning",
        "extra_footprint": "warning",
        "footprint_type_mismatch": "error",
        "hole_clearance": "error",
        "hole_near_hole": "error",
        "invalid_outline": "error",
        "item_on_disabled_layer": "error",
        "items_not_allowed": "error",
        "length_out_of_range": "error",
        "malformed_courtyard": "error",
        "microvia_drill_out_of_range": "error",
        "missing_courtyard": "ignore",
        "missing_footprint": "warning",
        "net_conflict": "warning",
        "npth_inside_courtyard": "ignore",
        "padstack": "error",
        "pth_inside_courtyard": "ignore",
        "shorting_items": "error",
        "silk_over_copper": "ignore",
        "silk_overlap": "warning",
        "skew_out_of_range": "error",
        "through_hole_pad_without_hole": "error",
        "too_many_vias": "error",
        "track_dangling": "warning",
        "track_width": "error",
        "tracks_crossing": "error",
        "unconnected_items": "error",
        "unresolved_variable": "error",
        "via_dangling": "warning",
        "zone_has_empty_net": "error",
        "zones_intersect": "error"
      },
      "rules": {
        "allow_blind_buried_vias": false,
        "allow_microvias": false,
        "max_error": 0.005,
        "min_clearance": 0.0,
        "min_copper_edge_clearance": 0.0,
        "min_hole_clearance": 0.25,
        "min_hole_to_hole": 0.25,
        "min_microvia_diameter": 0.19999999999999998,
        "min_microvia_drill": 0.09999999999999999,
        "min_silk_clearance": 0.0,
        "min_through_hole_diameter": 0.19999999999999998,
        "min_track_width": 0.09999999999999999,
        "min_via_annular_width": 0.049999999999999996,
        "min_via_diameter": 0.39999999999999997,
        "solder_mask_clearance": 0.0,
        "solder_mask_min_width": 0.0,
        "use_height_for_length_calcs": true
      },
      "track_widths": [
        0.0
      ],
      "via_dimensions": [
        {
          "diameter": 0.0,
          "drill": 0.0
        },
        {
          "diameter": 0.55,
          "drill": 0.2
        }
      ],
      "zones_allow_external_fillets": false,
      "zones_use_no_outline": true
    },
    "layer_presets": []
  },
  "boards": [],
  "cvpcb": {
    "equivalence_files": []
  },
  "erc": {
    "erc_exclusions": [],
    "meta": {
      "version": 0
    },
    "pin_map": [
      [
        0,
        0,
        0,
        0,
        0,
        0,
        1,
        0,
        0,
        0,
        0,
        2
      ],
      [
        0,
        2,
        0,
        1,
        0,
        0,
        1,
        0,
        2,
        2,
        2,
        2
      ],
      [
        0,
        0,
        0,
        0,
        0,
        0,
        1,
        0,
        1,
        0,
        1,
        2
      ],
      [
        0,
        1,
        0,
        0,
        0,
        0,
        1,
        1,
        2,
        1,
        1,
        2
      ],
      [
        0,
        0,
        0,
        0,
        0,
        0,
        1,
        0,
        0,
        0,
        0,
        2
      ],
      [
        0,
        0,
        0,
        0,
        0,
        0,
        0,
        0,
        0,
        0,
        0,
        2
      ],
      [
        1,
        1,
        1,
        1,
        1,
        0,
        1,
        1,
        1,
        1,
        1,
        2
      ],
      [
        0,
        0,
        0,
        1,
        0,
        0,
        1,
        0,
        0,
        0,
        0,
        2
      ],
      [
        0,
        2,
        1,
        2,
        0,
        0,
        1,
        0,
        2,
        2,
        2,
        2
      ],
      [
        0,
        2,
        0,
        1,
        0,
        0,
        1,
        0,
        2,
        0,
        0,
        2
      ],
      [
        0,
        2,
        1,
        1,
        0,
        0,
        1,
        0,
        2,
        0,
        0,
        2
      ],
      [
        2,
        2,
        2,
        2,
        2,
        2,
        2,
        2,
        2,
        2,
        2,
        2
      ]
    ],
    "rule_severities": {
      "bus_definition_conflict": "error",
      "bus_entry_needed": "error",
      "bus_label_syntax": "error",
      "bus_to_bus_conflict": "error",
      "bus_to_net_conflict": "error",
      "different_unit_footprint": "error",
      "different_unit_net": "error",
      "duplicate_reference": "error",
      "duplicate_sheet_names": "error",
      "extra_units": "error",
      "global_label_dangling": "warning",
      "hier_label_mismatch": "error",
      "label_dangling": "error",
      "lib_symbol_issues": "warning",
      "multiple_net_names": "warning",
      "net_not_bus_member": "warning",
      "no_connect_connected": "warning",
      "no_connect_dangling": "warning",
      "pin_not_connected": "error",
      "pin_not_driven": "error",
      "pin_to_pin": "warning",
      "power_pin_not_driven": "error",
      "similar_labels": "warning",
      "unannotated": "error",
      "unit_value_mismatch": "error",
      "unresolved_variable": "error",
      "wire_dangling": "error"
    }
  },
  "libraries": {
    "pinned_footprint_libs": [],
    "pinned_symbol_libs": []
  },
  "meta": {
    "filename": "si-simulation-test-board.kicad_pro",
    "version": 1
  },
  "net_settings": {
    "classes": [
      {
        "bus_width": 12.0,
        "clearance": 0.1,
        "diff_pair_gap": 0.15,
        "diff_pair_via_gap": 0.25,
        "diff_pair_width": 0.185,
        "line_style": 0,
        "microvia_diameter": 0.3,
        "microvia_drill": 0.1,
        "name": "Default",
        "pcb_color": "rgba(0, 0, 0, 0.000)",
        "schematic_color": "rgba(0, 0, 0, 0.000)",
        "track_width": 0.185,
        "via_diameter": 0.8,
        "via_drill": 0.4,
        "wire_width": 6.0
      },
      {
        "bus_width": 12.0,
        "clearance": 0.1,
        "diff_pair_gap": 0.25,
        "diff_pair_via_gap": 0.25,
        "diff_pair_width": 0.2,
        "line_style": 0,
        "microvia_diameter": 0.3,
        "microvia_drill": 0.1,
        "name": "50Ohm",
        "nets": [
          "Net-(J1-Pad1)"
        ],
        "pcb_color": "rgba(0, 0, 0, 0.000)",
        "schematic_color": "rgba(0, 0, 0, 0.000)",
        "track_width": 0.185,
        "via_diameter": 0.8,
        "via_drill": 0.4,
        "wire_width": 6.0
      }
    ],
    "meta": {
      "version": 2
    },
    "net_colors": null
  },
  "pcbnew": {
    "last_paths": {
      "gencad": "",
      "idf": "",
      "netlist": "",
      "specctra_dsn": "",
      "step": "",
      "vrml": ""
    },
    "page_layout_descr_file": ""
  },
  "schematic": {
    "annotate_start_num": 0,
    "drawing": {
      "default_line_thickness": 6.0,
      "default_text_size": 50.0,
      "field_names": [],
      "intersheets_ref_own_page": false,
      "intersheets_ref_prefix": "",
      "intersheets_ref_short": false,
      "intersheets_ref_show": false,
      "intersheets_ref_suffix": "",
      "junction_size_choice": 3,
      "label_size_ratio": 0.375,
      "pin_symbol_size": 25.0,
      "text_offset_ratio": 0.15
    },
    "legacy_lib_dir": "",
    "legacy_lib_list": [],
    "meta": {
      "version": 1
    },
    "net_format_name": "",
    "ngspice": {
      "fix_include_paths": true,
      "fix_passive_vals": false,
      "meta": {
        "version": 0
      },
      "model_mode": 0,
      "workbook_filename": ""
    },
    "page_layout_descr_file": "",
    "plot_directory": "",
    "spice_adjust_passive_values": false,
    "spice_external_command": "spice \"%I\"",
    "subpart_first_id": 65,
    "subpart_id_separator": 0
  },
  "sheets": [
    [
      "",
      ""
    ]
  ],
  "text_variables": {}
}
